FILE_TYPE = CONNECTIVITY;
{Allegro Design Entry HDL 17.2-2016 S081 (4005846) 1/11/2022}
"PAGE_NUMBER" = 203;
0"NC";
END.
